(kicad_pcb
	(version 20241229)
	(generator "pcbnew")
	(generator_version "9.0")
	(general
		(thickness 1.6)
		(legacy_teardrops no)
	)
	(paper "A4")
	(title_block
		(title "GMSL Deserializer")
		(date "2025-10-09")
		(rev "1.0.4")
		(company "Antmicro Ltd")
		(comment 1 "www.antmicro.com")
		(comment 9 "footprints 8-12 of 235")
	)
	(layers
		(0 "F.Cu" signal)
		(4 "In1.Cu" power)
		(6 "In2.Cu" power)
		(2 "B.Cu" signal)
		(9 "F.Adhes" user "F.Adhesive")
		(11 "B.Adhes" user "B.Adhesive")
		(13 "F.Paste" user)
		(15 "B.Paste" user)
		(5 "F.SilkS" user "F.Silkscreen")
		(7 "B.SilkS" user "B.Silkscreen")
		(1 "F.Mask" user)
		(3 "B.Mask" user)
		(17 "Dwgs.User" user "User.Drawings")
		(19 "Cmts.User" user "User.Comments")
		(21 "Eco1.User" user "User.Eco1")
		(23 "Eco2.User" user "User.Eco2")
		(25 "Edge.Cuts" user)
		(27 "Margin" user)
		(31 "F.CrtYd" user "F.Courtyard")
		(29 "B.CrtYd" user "B.Courtyard")
		(35 "F.Fab" user)
		(33 "B.Fab" user)
	)
	(footprint "antmicro-footprints:C_0402_1005Metric"
		(layer "F.Cu")
		(at 153.416 76.962 45)
		(descr "Capacitor SMD 0402")
		(tags "capacitor SMD 0402")
		(property "Reference" "C30"
			(at 3.970405 0.160513 45)
			(layer "F.SilkS")
			(effects
				(font
					(size 0.7 0.7)
					(thickness 0.15)
				)
				(justify left bottom)
			)
		)
		(property "Value" "C_100n_0402"
			(at -1.022927 2.155213 45)
			(layer "F.Fab")
			(effects
				(font
					(size 0.7 0.7)
					(thickness 0.15)
				)
				(justify left bottom)
			)
		)
		(property "Datasheet" "https://www.murata.com/products/productdetail?partno=GRM155R61H104KE14%23"
			(at 0 0 45)
			(layer "F.Fab")
			(hide yes)
			(effects
				(font
					(size 1.27 1.27)
					(thickness 0.15)
				)
			)
		)
		(property "Description" "SMD Multilayer Ceramic Capacitor, 0.1 µF, 50 V, 0402 [1005 Metric], ± 10%, X5R, GRM Series"
			(at 0 0 45)
			(layer "F.Fab")
			(hide yes)
			(effects
				(font
					(size 1.27 1.27)
					(thickness 0.15)
				)
			)
		)
		(property "Author" "Antmicro"
			(at 99.354858 -85.939846 0)
			(layer "F.Fab")
			(hide yes)
			(effects
				(font
					(size 1 1)
					(thickness 0.15)
				)
			)
		)
		(property "Dielectric" "X5R"
			(at 99.354858 -85.939846 0)
			(layer "F.Fab")
			(hide yes)
			(effects
				(font
					(size 1 1)
					(thickness 0.15)
				)
			)
		)
		(property "License" "Apache-2.0"
			(at 99.354858 -85.939846 0)
			(layer "F.Fab")
			(hide yes)
			(effects
				(font
					(size 1 1)
					(thickness 0.15)
				)
			)
		)
		(property "MPN" "GRM155R61H104KE14D"
			(at 99.354858 -85.939846 0)
			(layer "F.Fab")
			(hide yes)
			(effects
				(font
					(size 1 1)
					(thickness 0.15)
				)
			)
		)
		(property "Manufacturer" "Murata"
			(at 99.354858 -85.939846 0)
			(layer "F.Fab")
			(hide yes)
			(effects
				(font
					(size 1 1)
					(thickness 0.15)
				)
			)
		)
		(property "Val" "100n"
			(at 99.354858 -85.939846 0)
			(layer "F.Fab")
			(hide yes)
			(effects
				(font
					(size 1 1)
					(thickness 0.15)
				)
			)
		)
		(property "Voltage" "50V"
			(at 99.354858 -85.939846 0)
			(layer "F.Fab")
			(hide yes)
			(effects
				(font
					(size 1 1)
					(thickness 0.15)
				)
			)
		)
		(sheetname "/Deserializer/")
		(sheetfile "deserializer.kicad_sch")
		(attr smd)
		(fp_poly
			(pts
				(xy -0.925 -0.47) (xy 0.925 -0.47) (xy 0.925 0.47) (xy -0.925 0.47)
			)
			(stroke
				(width 0.05)
				(type default)
			)
			(fill no)
			(layer "F.CrtYd")
		)
		(fp_line
			(start -0.494 -0.25)
			(end 0.504 -0.25)
			(stroke
				(width 0.15)
				(type solid)
			)
			(layer "F.Fab")
		)
		(fp_line
			(start -0.494 0.248)
			(end -0.494 -0.25)
			(stroke
				(width 0.15)
				(type solid)
			)
			(layer "F.Fab")
		)
		(fp_line
			(start 0.504 -0.25)
			(end 0.504 0.248)
			(stroke
				(width 0.15)
				(type solid)
			)
			(layer "F.Fab")
		)
		(fp_line
			(start 0.504 0.248)
			(end -0.494 0.248)
			(stroke
				(width 0.15)
				(type solid)
			)
			(layer "F.Fab")
		)
		(pad "1" smd roundrect
			(at -0.48 0 45)
			(size 0.59 0.64)
			(layers "F.Cu" "F.Mask" "F.Paste")
			(roundrect_rratio 0.25)
			(net 16 "/Deserializer/SIOD_P")
			(pintype "passive")
		)
		(pad "2" smd roundrect
			(at 0.48 0 45)
			(size 0.59 0.64)
			(layers "F.Cu" "F.Mask" "F.Paste")
			(roundrect_rratio 0.25)
			(net 117 "/Connectors/PoCD")
			(pintype "passive")
		)
	)
	(footprint "antmicro-footprints:L_Coilcraft-PFL1609"
		(layer "F.Cu")
		(at 125.984 53.594)
		(property "Reference" "L9"
			(at -2.667 0.381 0)
			(layer "F.SilkS")
			(effects
				(font
					(size 0.7 0.7)
					(thickness 0.15)
				)
				(justify left bottom)
			)
		)
		(property "Value" "L_470n_1A_Coilcraft-PFL1609"
			(at 0 2 0)
			(layer "F.Fab")
			(effects
				(font
					(size 0.7 0.7)
					(thickness 0.15)
				)
				(justify left bottom)
			)
		)
		(property "Datasheet" "https://www.coilcraft.com/getmedia/2f4cd442-d64d-4413-a518-12fcfd03318d/pfl1609.pdf"
			(at 0 0 0)
			(layer "F.Fab")
			(hide yes)
			(effects
				(font
					(size 1.27 1.27)
					(thickness 0.15)
				)
			)
		)
		(property "Description" "Power Inductor (SMT), 6.8 µH, 9.2 A, Shielded, 12.8 A, XAL7070"
			(at 0 0 0)
			(layer "F.Fab")
			(hide yes)
			(effects
				(font
					(size 1.27 1.27)
					(thickness 0.15)
				)
			)
		)
		(property "Author" "Antmicro"
			(at 0 0 0)
			(layer "F.Fab")
			(hide yes)
			(effects
				(font
					(size 1 1)
					(thickness 0.15)
				)
			)
		)
		(property "IMax" "1 A"
			(at 0 0 0)
			(layer "F.Fab")
			(hide yes)
			(effects
				(font
					(size 1 1)
					(thickness 0.15)
				)
			)
		)
		(property "ISat" "0.99 A"
			(at 0 0 0)
			(layer "F.Fab")
			(hide yes)
			(effects
				(font
					(size 1 1)
					(thickness 0.15)
				)
			)
		)
		(property "License" "Apache-2.0"
			(at 0 0 0)
			(layer "F.Fab")
			(hide yes)
			(effects
				(font
					(size 1 1)
					(thickness 0.15)
				)
			)
		)
		(property "MPN" "PFL1609-471"
			(at 0 0 0)
			(layer "F.Fab")
			(hide yes)
			(effects
				(font
					(size 1 1)
					(thickness 0.15)
				)
			)
		)
		(property "Manufacturer" "Coilcraft"
			(at 0 0 0)
			(layer "F.Fab")
			(hide yes)
			(effects
				(font
					(size 1 1)
					(thickness 0.15)
				)
			)
		)
		(property "Size" "1.07x1.8"
			(at 0 0 0)
			(layer "F.Fab")
			(hide yes)
			(effects
				(font
					(size 1 1)
					(thickness 0.15)
				)
			)
		)
		(property "Val" "470n/0.99A"
			(at 0 0 0)
			(layer "F.Fab")
			(hide yes)
			(effects
				(font
					(size 1 1)
					(thickness 0.15)
				)
			)
		)
		(sheetname "/Power/")
		(sheetfile "power.kicad_sch")
		(attr smd)
		(fp_line
			(start -0.23 -0.45)
			(end 0.23 -0.45)
			(stroke
				(width 0.15)
				(type solid)
			)
			(layer "F.SilkS")
		)
		(fp_line
			(start -0.23 0.45)
			(end 0.23 0.45)
			(stroke
				(width 0.15)
				(type solid)
			)
			(layer "F.SilkS")
		)
		(fp_rect
			(start -1.2 -0.84)
			(end 1.2 0.84)
			(stroke
				(width 0.05)
				(type solid)
			)
			(fill no)
			(layer "F.CrtYd")
		)
		(fp_rect
			(start -0.9 -0.535)
			(end 0.9 0.535)
			(stroke
				(width 0.15)
				(type solid)
			)
			(fill no)
			(layer "F.Fab")
		)
		(pad "1" smd roundrect
			(at -0.635 0)
			(size 0.64 1.02)
			(layers "F.Cu" "F.Mask" "F.Paste")
			(roundrect_rratio 0.15)
			(net 55 "Net-(L5-Pad2)")
			(pintype "passive")
		)
		(pad "2" smd roundrect
			(at 0.635 0)
			(size 0.64 1.02)
			(layers "F.Cu" "F.Mask" "F.Paste")
			(roundrect_rratio 0.15)
			(net 59 "Net-(L13-Pad1)")
			(pintype "passive")
		)
	)
	(footprint "antmicro-footprints:L_Coilcraft-PFL1609"
		(layer "F.Cu")
		(at 137.668 53.594)
		(property "Reference" "L10"
			(at -3.147 0.381 0)
			(layer "F.SilkS")
			(effects
				(font
					(size 0.7 0.7)
					(thickness 0.15)
				)
				(justify left bottom)
			)
		)
		(property "Value" "L_470n_1A_Coilcraft-PFL1609"
			(at 0 2 0)
			(layer "F.Fab")
			(effects
				(font
					(size 0.7 0.7)
					(thickness 0.15)
				)
				(justify left bottom)
			)
		)
		(property "Datasheet" "https://www.coilcraft.com/getmedia/2f4cd442-d64d-4413-a518-12fcfd03318d/pfl1609.pdf"
			(at 0 0 0)
			(layer "F.Fab")
			(hide yes)
			(effects
				(font
					(size 1.27 1.27)
					(thickness 0.15)
				)
			)
		)
		(property "Description" "Power Inductor (SMT), 6.8 µH, 9.2 A, Shielded, 12.8 A, XAL7070"
			(at 0 0 0)
			(layer "F.Fab")
			(hide yes)
			(effects
				(font
					(size 1.27 1.27)
					(thickness 0.15)
				)
			)
		)
		(property "Author" "Antmicro"
			(at 0 0 0)
			(layer "F.Fab")
			(hide yes)
			(effects
				(font
					(size 1 1)
					(thickness 0.15)
				)
			)
		)
		(property "IMax" "1 A"
			(at 0 0 0)
			(layer "F.Fab")
			(hide yes)
			(effects
				(font
					(size 1 1)
					(thickness 0.15)
				)
			)
		)
		(property "ISat" "0.99 A"
			(at 0 0 0)
			(layer "F.Fab")
			(hide yes)
			(effects
				(font
					(size 1 1)
					(thickness 0.15)
				)
			)
		)
		(property "License" "Apache-2.0"
			(at 0 0 0)
			(layer "F.Fab")
			(hide yes)
			(effects
				(font
					(size 1 1)
					(thickness 0.15)
				)
			)
		)
		(property "MPN" "PFL1609-471"
			(at 0 0 0)
			(layer "F.Fab")
			(hide yes)
			(effects
				(font
					(size 1 1)
					(thickness 0.15)
				)
			)
		)
		(property "Manufacturer" "Coilcraft"
			(at 0 0 0)
			(layer "F.Fab")
			(hide yes)
			(effects
				(font
					(size 1 1)
					(thickness 0.15)
				)
			)
		)
		(property "Size" "1.07x1.8"
			(at 0 0 0)
			(layer "F.Fab")
			(hide yes)
			(effects
				(font
					(size 1 1)
					(thickness 0.15)
				)
			)
		)
		(property "Val" "470n/0.99A"
			(at 0 0 0)
			(layer "F.Fab")
			(hide yes)
			(effects
				(font
					(size 1 1)
					(thickness 0.15)
				)
			)
		)
		(sheetname "/Power/")
		(sheetfile "power.kicad_sch")
		(attr smd)
		(fp_line
			(start -0.23 -0.45)
			(end 0.23 -0.45)
			(stroke
				(width 0.15)
				(type solid)
			)
			(layer "F.SilkS")
		)
		(fp_line
			(start -0.23 0.45)
			(end 0.23 0.45)
			(stroke
				(width 0.15)
				(type solid)
			)
			(layer "F.SilkS")
		)
		(fp_rect
			(start -1.2 -0.84)
			(end 1.2 0.84)
			(stroke
				(width 0.05)
				(type solid)
			)
			(fill no)
			(layer "F.CrtYd")
		)
		(fp_rect
			(start -0.9 -0.535)
			(end 0.9 0.535)
			(stroke
				(width 0.15)
				(type solid)
			)
			(fill no)
			(layer "F.Fab")
		)
		(pad "1" smd roundrect
			(at -0.635 0)
			(size 0.64 1.02)
			(layers "F.Cu" "F.Mask" "F.Paste")
			(roundrect_rratio 0.15)
			(net 56 "Net-(L10-Pad1)")
			(pintype "passive")
		)
		(pad "2" smd roundrect
			(at 0.635 0)
			(size 0.64 1.02)
			(layers "F.Cu" "F.Mask" "F.Paste")
			(roundrect_rratio 0.15)
			(net 60 "Net-(L10-Pad2)")
			(pintype "passive")
		)
	)
	(footprint "antmicro-footprints:C_0402_1005Metric"
		(layer "F.Cu")
		(at 172.212 62.103 -90)
		(descr "Capacitor SMD 0402")
		(tags "capacitor SMD 0402")
		(property "Reference" "C3"
			(at -0.903 -1.288 90)
			(layer "F.SilkS")
			(effects
				(font
					(size 0.7 0.7)
					(thickness 0.15)
				)
				(justify right bottom)
			)
		)
		(property "Value" "C_100n_0402"
			(at -1.022927 2.155213 90)
			(layer "F.Fab")
			(effects
				(font
					(size 0.7 0.7)
					(thickness 0.15)
				)
				(justify right bottom)
			)
		)
		(property "Datasheet" "https://www.murata.com/products/productdetail?partno=GRM155R61H104KE14%23"
			(at 0 0 270)
			(layer "F.Fab")
			(hide yes)
			(effects
				(font
					(size 1.27 1.27)
					(thickness 0.15)
				)
			)
		)
		(property "Description" "SMD Multilayer Ceramic Capacitor, 0.1 µF, 50 V, 0402 [1005 Metric], ± 10%, X5R, GRM Series"
			(at 0 0 270)
			(layer "F.Fab")
			(hide yes)
			(effects
				(font
					(size 1.27 1.27)
					(thickness 0.15)
				)
			)
		)
		(property "Author" "Antmicro"
			(at 110.109 234.315 0)
			(layer "F.Fab")
			(hide yes)
			(effects
				(font
					(size 1 1)
					(thickness 0.15)
				)
			)
		)
		(property "Dielectric" "X5R"
			(at 110.109 234.315 0)
			(layer "F.Fab")
			(hide yes)
			(effects
				(font
					(size 1 1)
					(thickness 0.15)
				)
			)
		)
		(property "License" "Apache-2.0"
			(at 110.109 234.315 0)
			(layer "F.Fab")
			(hide yes)
			(effects
				(font
					(size 1 1)
					(thickness 0.15)
				)
			)
		)
		(property "MPN" "GRM155R61H104KE14D"
			(at 110.109 234.315 0)
			(layer "F.Fab")
			(hide yes)
			(effects
				(font
					(size 1 1)
					(thickness 0.15)
				)
			)
		)
		(property "Manufacturer" "Murata"
			(at 110.109 234.315 0)
			(layer "F.Fab")
			(hide yes)
			(effects
				(font
					(size 1 1)
					(thickness 0.15)
				)
			)
		)
		(property "Val" "100n"
			(at 110.109 234.315 0)
			(layer "F.Fab")
			(hide yes)
			(effects
				(font
					(size 1 1)
					(thickness 0.15)
				)
			)
		)
		(property "Voltage" "50V"
			(at 110.109 234.315 0)
			(layer "F.Fab")
			(hide yes)
			(effects
				(font
					(size 1 1)
					(thickness 0.15)
				)
			)
		)
		(sheetname "/Connectors/")
		(sheetfile "connectors.kicad_sch")
		(attr smd)
		(fp_rect
			(start -0.925 -0.47)
			(end 0.925 0.47)
			(stroke
				(width 0.05)
				(type default)
			)
			(fill no)
			(layer "F.CrtYd")
		)
		(fp_line
			(start -0.494 0.248)
			(end -0.494 -0.25)
			(stroke
				(width 0.15)
				(type solid)
			)
			(layer "F.Fab")
		)
		(fp_line
			(start 0.504 0.248)
			(end -0.494 0.248)
			(stroke
				(width 0.15)
				(type solid)
			)
			(layer "F.Fab")
		)
		(fp_line
			(start -0.494 -0.25)
			(end 0.504 -0.25)
			(stroke
				(width 0.15)
				(type solid)
			)
			(layer "F.Fab")
		)
		(fp_line
			(start 0.504 -0.25)
			(end 0.504 0.248)
			(stroke
				(width 0.15)
				(type solid)
			)
			(layer "F.Fab")
		)
		(pad "1" smd roundrect
			(at -0.48 0 270)
			(size 0.59 0.64)
			(layers "F.Cu" "F.Mask" "F.Paste")
			(roundrect_rratio 0.25)
			(net 1 "GND")
			(pintype "passive")
		)
		(pad "2" smd roundrect
			(at 0.48 0 270)
			(size 0.59 0.64)
			(layers "F.Cu" "F.Mask" "F.Paste")
			(roundrect_rratio 0.25)
			(net 3 "+1V8")
			(pintype "passive")
		)
	)
	(footprint "antmicro-footprints:R_0603_1608Metric"
		(layer "F.Cu")
		(at 131.725 90.538 90)
		(descr "Resistor SMD 0603")
		(tags "resistor SMD 0603")
		(property "Reference" "R40"
			(at -1.016 -0.9 90)
			(layer "F.SilkS")
			(effects
				(font
					(size 0.7 0.7)
					(thickness 0.15)
				)
				(justify left bottom)
			)
		)
		(property "Value" "R_0R_22.4A_0603"
			(at -5.1615 1.6 90)
			(layer "F.Fab")
			(effects
				(font
					(size 0.7 0.7)
					(thickness 0.15)
				)
				(justify left bottom)
			)
		)
		(property "Datasheet" "https://fscdn.rohm.com/en/products/databook/datasheet/passive/resistor/chip_resistor/pmr-jpw-e.pdf"
			(at 0 0 90)
			(layer "F.Fab")
			(hide yes)
			(effects
				(font
					(size 1.27 1.27)
					(thickness 0.15)
				)
			)
		)
		(property "Description" "SMD Chip Resistor"
			(at 0 0 90)
			(layer "F.Fab")
			(hide yes)
			(effects
				(font
					(size 1.27 1.27)
					(thickness 0.15)
				)
			)
		)
		(property "Author" "Antmicro"
			(at 222.263 -41.187 0)
			(layer "F.Fab")
			(hide yes)
			(effects
				(font
					(size 1 1)
					(thickness 0.15)
				)
			)
		)
		(property "License" "Apache-2.0"
			(at 222.263 -41.187 0)
			(layer "F.Fab")
			(hide yes)
			(effects
				(font
					(size 1 1)
					(thickness 0.15)
				)
			)
		)
		(property "MPN" "PMR03EZPJ000"
			(at 222.263 -41.187 0)
			(layer "F.Fab")
			(hide yes)
			(effects
				(font
					(size 1 1)
					(thickness 0.15)
				)
			)
		)
		(property "Manufacturer" "ROHM Semiconductor"
			(at 222.263 -41.187 0)
			(layer "F.Fab")
			(hide yes)
			(effects
				(font
					(size 1 1)
					(thickness 0.15)
				)
			)
		)
		(property "Max. Curr." "22.4A"
			(at 222.263 -41.187 0)
			(layer "F.Fab")
			(hide yes)
			(effects
				(font
					(size 1 1)
					(thickness 0.15)
				)
			)
		)
		(property "Tolerance" "template_tolerance"
			(at 222.263 -41.187 0)
			(layer "F.Fab")
			(hide yes)
			(effects
				(font
					(size 1 1)
					(thickness 0.15)
				)
			)
		)
		(property "Val" "0R"
			(at 222.263 -41.187 0)
			(layer "F.Fab")
			(hide yes)
			(effects
				(font
					(size 1 1)
					(thickness 0.15)
				)
			)
		)
		(sheetname "/Power/")
		(sheetfile "power.kicad_sch")
		(attr smd)
		(fp_line
			(start -0.15 -0.4)
			(end 0.15 -0.4)
			(stroke
				(width 0.15)
				(type solid)
			)
			(layer "F.SilkS")
		)
		(fp_line
			(start -0.15 0.4)
			(end 0.15 0.4)
			(stroke
				(width 0.15)
				(type solid)
			)
			(layer "F.SilkS")
		)
		(fp_rect
			(start -1.25 -0.65)
			(end 1.25 0.65)
			(stroke
				(width 0.05)
				(type solid)
			)
			(fill no)
			(layer "F.CrtYd")
		)
		(fp_rect
			(start -0.8 -0.4)
			(end 0.8 0.4)
			(stroke
				(width 0.15)
				(type solid)
			)
			(fill no)
			(layer "F.Fab")
		)
		(pad "1" smd roundrect
			(at -0.7 0 90)
			(size 0.8 1)
			(layers "F.Cu" "F.Mask" "F.Paste")
			(roundrect_rratio 0.2)
			(net 10 "/Power/OUT_1V8")
			(pintype "passive")
		)
		(pad "2" smd roundrect
			(at 0.7 0 90)
			(size 0.8 1)
			(layers "F.Cu" "F.Mask" "F.Paste")
			(roundrect_rratio 0.2)
			(net 3 "+1V8")
			(pintype "passive")
		)
	)
)
